# T6G (Grand Teton) — schematic netlist excerpt (pin names and nets, part order shuffled) for the footprints in the layout excerpt that follows; sources: Cadence DE-HDL packaged netlist, KiCad conversion of 04192023_DAF0TMB3IC0_F0TG_MB_C_brd_V02_OCP.brd

R3923  Q_RES  63.4K 1% CHIP  pkg 0402LF  page 268 : A = P12V_PSU_FUSE ; B = PDB_PRSNT_R_N
R9011  Q_RES  0 5% CHIP  pkg 0402LF  page 245 : A = PRSNT_CABLE_GPU_B3_ISO_N ; B = PRSNT_CABLE_GPU_B3_ISO_R1_N

(kicad_pcb
	(version 20260206)
	(generator "pcbnew")
	(generator_version "10.0")
	(general
		(thickness 1.6)
		(legacy_teardrops no)
	)
	(paper "A4")
	(title_block
		(title "04192023_DAF0TMB3IC0_F0TG_MB_C_brd_V02_OCP.brd")
		(comment 1 "Grand Teton / footprints 2298-2299 of 8354")
	)
	(layers
		(0 "F.Cu" signal "TOP")
		(4 "In1.Cu" signal "GND")
		(6 "In2.Cu" signal "IN1")
		(8 "In3.Cu" signal "GND1")
		(10 "In4.Cu" signal "IN2")
		(12 "In5.Cu" signal "GND2")
		(14 "In6.Cu" signal "IN3")
		(16 "In7.Cu" signal "GND3")
		(18 "In8.Cu" signal "VCC")
		(20 "In9.Cu" signal "VCC1")
		(22 "In10.Cu" signal "GND4")
		(24 "In11.Cu" signal "IN4")
		(26 "In12.Cu" signal "GND5")
		(28 "In13.Cu" signal "IN5")
		(30 "In14.Cu" signal "GND6")
		(32 "In15.Cu" signal "IN6")
		(34 "In16.Cu" signal "GND7")
		(2 "B.Cu" signal "BOTTOM")
		(9 "F.Adhes" user "F.Adhesive")
		(11 "B.Adhes" user "B.Adhesive")
		(13 "F.Paste" user "Package Geometry/Pastemask Top")
		(15 "B.Paste" user "Package Geometry/Pastemask Bottom")
		(5 "F.SilkS" user "Ref Des/Silkscreen Top")
		(7 "B.SilkS" user "Ref Des/Silkscreen Bottom")
		(1 "F.Mask" user "Board Geometry/Soldermask Top")
		(3 "B.Mask" user "Board Geometry/Soldermask Bottom")
		(17 "Dwgs.User" user "User.Drawings")
		(19 "Cmts.User" user "User.Comments")
		(21 "Eco1.User" user "User.Eco1")
		(23 "Eco2.User" user "User.Eco2")
		(25 "Edge.Cuts" user "Board Geometry/Outline")
		(27 "Margin" user)
		(31 "F.CrtYd" user "Package Geometry/Place Bound Top")
		(29 "B.CrtYd" user "Package Geometry/Place Bound Bottom")
		(35 "F.Fab" user "Ref Des/Assembly Top")
		(33 "B.Fab" user "Ref Des/Assembly Bottom")
	)
	(footprint ""
		(layer "F.Cu")
		(at 187.127642 -413.64408 90)
		(property "Reference" "R9011"
			(at 0 0 90)
			(layer "F.SilkS")
			(hide yes)
			(effects
				(font
					(size 1.27 1.27)
				)
			)
		)
		(property "Value" ""
			(at 0 0 90)
			(layer "F.Fab")
			(effects
				(font
					(size 1.27 1.27)
				)
			)
		)
		(duplicate_pad_numbers_are_jumpers no)
		(fp_line
			(start 0.7874 -0.4064)
			(end 0.7874 0.4064)
			(stroke
				(width 0.1524)
				(type default)
			)
			(layer "F.SilkS")
		)
		(fp_line
			(start -0.7874 -0.4064)
			(end 0.7874 -0.4064)
			(stroke
				(width 0.1524)
				(type default)
			)
			(layer "F.SilkS")
		)
		(fp_line
			(start 0.7874 0.4064)
			(end -0.7874 0.4064)
			(stroke
				(width 0.1524)
				(type default)
			)
			(layer "F.SilkS")
		)
		(fp_line
			(start -0.7874 0.4064)
			(end -0.7874 -0.4064)
			(stroke
				(width 0.1524)
				(type default)
			)
			(layer "F.SilkS")
		)
		(fp_line
			(start -0.12065 -0.305054)
			(end -0.12065 -0.2794)
			(stroke
				(width 0.1)
				(type default)
			)
			(layer "F.Fab")
		)
		(fp_line
			(start -0.67945 -0.305054)
			(end -0.12065 -0.305054)
			(stroke
				(width 0.1)
				(type default)
			)
			(layer "F.Fab")
		)
		(fp_line
			(start 0.67945 -0.3048)
			(end 0.67945 0.3048)
			(stroke
				(width 0.1)
				(type default)
			)
			(layer "F.Fab")
		)
		(fp_line
			(start 0.12065 -0.3048)
			(end 0.67945 -0.3048)
			(stroke
				(width 0.1)
				(type default)
			)
			(layer "F.Fab")
		)
		(fp_line
			(start 0.12065 -0.2794)
			(end 0.12065 -0.3048)
			(stroke
				(width 0.1)
				(type default)
			)
			(layer "F.Fab")
		)
		(fp_line
			(start -0.12065 -0.2794)
			(end 0.12065 -0.2794)
			(stroke
				(width 0.1)
				(type default)
			)
			(layer "F.Fab")
		)
		(fp_line
			(start 0.120396 0.2794)
			(end -0.12065 0.2794)
			(stroke
				(width 0.1)
				(type default)
			)
			(layer "F.Fab")
		)
		(fp_line
			(start -0.12065 0.2794)
			(end -0.12065 0.3048)
			(stroke
				(width 0.1)
				(type default)
			)
			(layer "F.Fab")
		)
		(fp_line
			(start 0.67945 0.3048)
			(end 0.120396 0.3048)
			(stroke
				(width 0.1)
				(type default)
			)
			(layer "F.Fab")
		)
		(fp_line
			(start 0.120396 0.3048)
			(end 0.120396 0.2794)
			(stroke
				(width 0.1)
				(type default)
			)
			(layer "F.Fab")
		)
		(fp_line
			(start -0.12065 0.3048)
			(end -0.67945 0.3048)
			(stroke
				(width 0.1)
				(type default)
			)
			(layer "F.Fab")
		)
		(fp_line
			(start -0.67945 0.3048)
			(end -0.67945 -0.305054)
			(stroke
				(width 0.1)
				(type default)
			)
			(layer "F.Fab")
		)
		(pad "1" smd circle
			(at -0.40005 0 90)
			(size 0 0)
			(layers "F.Cu" "F.Mask" "F.Paste")
			(net "PRSNT_CABLE_GPU_B3_ISO_N")
		)
		(pad "2" smd circle
			(at 0.40005 0 90)
			(size 0 0)
			(layers "F.Cu" "F.Mask" "F.Paste")
			(net "PRSNT_CABLE_GPU_B3_ISO_R1_N")
		)
	)
	(footprint ""
		(layer "F.Cu")
		(at 265.16838 -419.628828)
		(property "Reference" "R3923"
			(at 0 0 0)
			(layer "F.SilkS")
			(hide yes)
			(effects
				(font
					(size 1.27 1.27)
				)
			)
		)
		(property "Value" ""
			(at 0 0 0)
			(layer "F.Fab")
			(effects
				(font
					(size 1.27 1.27)
				)
			)
		)
		(duplicate_pad_numbers_are_jumpers no)
		(fp_line
			(start -0.7874 -0.4064)
			(end 0.7874 -0.4064)
			(stroke
				(width 0.1524)
				(type default)
			)
			(layer "F.SilkS")
		)
		(fp_line
			(start -0.7874 0.4064)
			(end -0.7874 -0.4064)
			(stroke
				(width 0.1524)
				(type default)
			)
			(layer "F.SilkS")
		)
		(fp_line
			(start 0.7874 -0.4064)
			(end 0.7874 0.4064)
			(stroke
				(width 0.1524)
				(type default)
			)
			(layer "F.SilkS")
		)
		(fp_line
			(start 0.7874 0.4064)
			(end -0.7874 0.4064)
			(stroke
				(width 0.1524)
				(type default)
			)
			(layer "F.SilkS")
		)
		(fp_line
			(start -0.67945 -0.305054)
			(end -0.12065 -0.305054)
			(stroke
				(width 0.1)
				(type default)
			)
			(layer "F.Fab")
		)
		(fp_line
			(start -0.67945 0.3048)
			(end -0.67945 -0.305054)
			(stroke
				(width 0.1)
				(type default)
			)
			(layer "F.Fab")
		)
		(fp_line
			(start -0.12065 -0.305054)
			(end -0.12065 -0.2794)
			(stroke
				(width 0.1)
				(type default)
			)
			(layer "F.Fab")
		)
		(fp_line
			(start -0.12065 -0.2794)
			(end 0.12065 -0.2794)
			(stroke
				(width 0.1)
				(type default)
			)
			(layer "F.Fab")
		)
		(fp_line
			(start -0.12065 0.2794)
			(end -0.12065 0.3048)
			(stroke
				(width 0.1)
				(type default)
			)
			(layer "F.Fab")
		)
		(fp_line
			(start -0.12065 0.3048)
			(end -0.67945 0.3048)
			(stroke
				(width 0.1)
				(type default)
			)
			(layer "F.Fab")
		)
		(fp_line
			(start 0.120396 0.2794)
			(end -0.12065 0.2794)
			(stroke
				(width 0.1)
				(type default)
			)
			(layer "F.Fab")
		)
		(fp_line
			(start 0.120396 0.3048)
			(end 0.120396 0.2794)
			(stroke
				(width 0.1)
				(type default)
			)
			(layer "F.Fab")
		)
		(fp_line
			(start 0.12065 -0.3048)
			(end 0.67945 -0.3048)
			(stroke
				(width 0.1)
				(type default)
			)
			(layer "F.Fab")
		)
		(fp_line
			(start 0.12065 -0.2794)
			(end 0.12065 -0.3048)
			(stroke
				(width 0.1)
				(type default)
			)
			(layer "F.Fab")
		)
		(fp_line
			(start 0.67945 -0.3048)
			(end 0.67945 0.3048)
			(stroke
				(width 0.1)
				(type default)
			)
			(layer "F.Fab")
		)
		(fp_line
			(start 0.67945 0.3048)
			(end 0.120396 0.3048)
			(stroke
				(width 0.1)
				(type default)
			)
			(layer "F.Fab")
		)
		(pad "1" smd circle
			(at -0.40005 0)
			(size 0 0)
			(layers "F.Cu" "F.Mask" "F.Paste")
			(net "P12V_PSU_FUSE")
		)
		(pad "2" smd circle
			(at 0.40005 0)
			(size 0 0)
			(layers "F.Cu" "F.Mask" "F.Paste")
			(net "PDB_PRSNT_R_N")
		)
	)
)
